# S9S_MB_2U (Grand Teton) — schematic netlist excerpt (pin names and nets, part order shuffled) for the footprints in the layout excerpt that follows; sources: Cadence DE-HDL packaged netlist, KiCad conversion of 03242023_DA0F0TMBIJ0_F0T_Motherboard_J_brd_V01_OCP.brd

R2455  Q_RES  33.2 1% CHIP  pkg 0402LF  page 241 : A = SMB_VR_3V3AUX_SCL_R ; B = SMB_VR_3V3AUX_SCL_R3
C438  Q_CAP  22UF 4V 20% X6S  pkg C0402  page 77 : A = PVCCINFAON_CPU1 ; B = GND

(kicad_pcb
	(version 20260206)
	(generator "pcbnew")
	(generator_version "10.0")
	(general
		(thickness 1.6)
		(legacy_teardrops no)
	)
	(paper "A4")
	(title_block
		(title "03242023_DA0F0TMBIJ0_F0T_Motherboard_J_brd_V01_OCP.brd")
		(comment 1 "Grand Teton / footprints 782-783 of 6105")
	)
	(layers
		(0 "F.Cu" signal "TOP")
		(4 "In1.Cu" signal "GND")
		(6 "In2.Cu" signal "IN1")
		(8 "In3.Cu" signal "GND1")
		(10 "In4.Cu" signal "IN2")
		(12 "In5.Cu" signal "GND2")
		(14 "In6.Cu" signal "IN3")
		(16 "In7.Cu" signal "GND3")
		(18 "In8.Cu" signal "VCC")
		(20 "In9.Cu" signal "VCC1")
		(22 "In10.Cu" signal "GND4")
		(24 "In11.Cu" signal "IN4")
		(26 "In12.Cu" signal "GND5")
		(28 "In13.Cu" signal "IN5")
		(30 "In14.Cu" signal "GND6")
		(32 "In15.Cu" signal "IN6")
		(34 "In16.Cu" signal "GND7")
		(2 "B.Cu" signal "BOTTOM")
		(9 "F.Adhes" user "F.Adhesive")
		(11 "B.Adhes" user "B.Adhesive")
		(13 "F.Paste" user "Package Geometry/Pastemask Top")
		(15 "B.Paste" user "Package Geometry/Pastemask Bottom")
		(5 "F.SilkS" user "Ref Des/Silkscreen Top")
		(7 "B.SilkS" user "Ref Des/Silkscreen Bottom")
		(1 "F.Mask" user "Board Geometry/Soldermask Top")
		(3 "B.Mask" user "Board Geometry/Soldermask Bottom")
		(17 "Dwgs.User" user "User.Drawings")
		(19 "Cmts.User" user "User.Comments")
		(21 "Eco1.User" user "User.Eco1")
		(23 "Eco2.User" user "User.Eco2")
		(25 "Edge.Cuts" user "Board Geometry/Outline")
		(27 "Margin" user)
		(31 "F.CrtYd" user "Package Geometry/Place Bound Top")
		(29 "B.CrtYd" user "Package Geometry/Place Bound Bottom")
		(35 "F.Fab" user "Ref Des/Assembly Top")
		(33 "B.Fab" user "Ref Des/Assembly Bottom")
	)
	(footprint ""
		(layer "F.Cu")
		(at 118.542816 -238.162592 90)
		(property "Reference" "C438"
			(at 0 0 90)
			(layer "F.SilkS")
			(hide yes)
			(effects
				(font
					(size 1.27 1.27)
				)
			)
		)
		(property "Value" ""
			(at 0 0 90)
			(layer "F.Fab")
			(effects
				(font
					(size 1.27 1.27)
				)
			)
		)
		(duplicate_pad_numbers_are_jumpers no)
		(fp_line
			(start 0.7874 -0.4064)
			(end 0.7874 0.4064)
			(stroke
				(width 0.1524)
				(type default)
			)
			(layer "F.SilkS")
		)
		(fp_line
			(start -0.7874 -0.4064)
			(end 0.7874 -0.4064)
			(stroke
				(width 0.1524)
				(type default)
			)
			(layer "F.SilkS")
		)
		(fp_line
			(start 0.7874 0.4064)
			(end -0.7874 0.4064)
			(stroke
				(width 0.1524)
				(type default)
			)
			(layer "F.SilkS")
		)
		(fp_line
			(start -0.7874 0.4064)
			(end -0.7874 -0.4064)
			(stroke
				(width 0.1524)
				(type default)
			)
			(layer "F.SilkS")
		)
		(fp_line
			(start -0.12065 -0.305054)
			(end -0.12065 -0.2794)
			(stroke
				(width 0.1)
				(type default)
			)
			(layer "F.Fab")
		)
		(fp_line
			(start -0.67945 -0.305054)
			(end -0.12065 -0.305054)
			(stroke
				(width 0.1)
				(type default)
			)
			(layer "F.Fab")
		)
		(fp_line
			(start 0.67945 -0.3048)
			(end 0.67945 0.3048)
			(stroke
				(width 0.1)
				(type default)
			)
			(layer "F.Fab")
		)
		(fp_line
			(start 0.12065 -0.3048)
			(end 0.67945 -0.3048)
			(stroke
				(width 0.1)
				(type default)
			)
			(layer "F.Fab")
		)
		(fp_line
			(start 0.12065 -0.2794)
			(end 0.12065 -0.3048)
			(stroke
				(width 0.1)
				(type default)
			)
			(layer "F.Fab")
		)
		(fp_line
			(start -0.12065 -0.2794)
			(end 0.12065 -0.2794)
			(stroke
				(width 0.1)
				(type default)
			)
			(layer "F.Fab")
		)
		(fp_line
			(start 0.120396 0.2794)
			(end -0.12065 0.2794)
			(stroke
				(width 0.1)
				(type default)
			)
			(layer "F.Fab")
		)
		(fp_line
			(start -0.12065 0.2794)
			(end -0.12065 0.3048)
			(stroke
				(width 0.1)
				(type default)
			)
			(layer "F.Fab")
		)
		(fp_line
			(start 0.67945 0.3048)
			(end 0.120396 0.3048)
			(stroke
				(width 0.1)
				(type default)
			)
			(layer "F.Fab")
		)
		(fp_line
			(start 0.120396 0.3048)
			(end 0.120396 0.2794)
			(stroke
				(width 0.1)
				(type default)
			)
			(layer "F.Fab")
		)
		(fp_line
			(start -0.12065 0.3048)
			(end -0.67945 0.3048)
			(stroke
				(width 0.1)
				(type default)
			)
			(layer "F.Fab")
		)
		(fp_line
			(start -0.67945 0.3048)
			(end -0.67945 -0.305054)
			(stroke
				(width 0.1)
				(type default)
			)
			(layer "F.Fab")
		)
		(pad "1" smd circle
			(at -0.40005 0 90)
			(size 0 0)
			(layers "F.Cu" "F.Mask" "F.Paste")
			(net "PVCCINFAON_CPU1")
		)
		(pad "2" smd circle
			(at 0.40005 0 90)
			(size 0 0)
			(layers "F.Cu" "F.Mask" "F.Paste")
			(net "GND")
		)
	)
	(footprint ""
		(layer "F.Cu")
		(at 101.071172 -362.602526)
		(property "Reference" "R2455"
			(at 0 0 0)
			(layer "F.SilkS")
			(hide yes)
			(effects
				(font
					(size 1.27 1.27)
				)
			)
		)
		(property "Value" ""
			(at 0 0 0)
			(layer "F.Fab")
			(effects
				(font
					(size 1.27 1.27)
				)
			)
		)
		(duplicate_pad_numbers_are_jumpers no)
		(fp_line
			(start -0.7874 -0.4064)
			(end 0.7874 -0.4064)
			(stroke
				(width 0.1524)
				(type default)
			)
			(layer "F.SilkS")
		)
		(fp_line
			(start -0.7874 0.4064)
			(end -0.7874 -0.4064)
			(stroke
				(width 0.1524)
				(type default)
			)
			(layer "F.SilkS")
		)
		(fp_line
			(start 0.7874 -0.4064)
			(end 0.7874 0.4064)
			(stroke
				(width 0.1524)
				(type default)
			)
			(layer "F.SilkS")
		)
		(fp_line
			(start 0.7874 0.4064)
			(end -0.7874 0.4064)
			(stroke
				(width 0.1524)
				(type default)
			)
			(layer "F.SilkS")
		)
		(fp_line
			(start -0.67945 -0.305054)
			(end -0.12065 -0.305054)
			(stroke
				(width 0.1)
				(type default)
			)
			(layer "F.Fab")
		)
		(fp_line
			(start -0.67945 0.3048)
			(end -0.67945 -0.305054)
			(stroke
				(width 0.1)
				(type default)
			)
			(layer "F.Fab")
		)
		(fp_line
			(start -0.12065 -0.305054)
			(end -0.12065 -0.2794)
			(stroke
				(width 0.1)
				(type default)
			)
			(layer "F.Fab")
		)
		(fp_line
			(start -0.12065 -0.2794)
			(end 0.12065 -0.2794)
			(stroke
				(width 0.1)
				(type default)
			)
			(layer "F.Fab")
		)
		(fp_line
			(start -0.12065 0.2794)
			(end -0.12065 0.3048)
			(stroke
				(width 0.1)
				(type default)
			)
			(layer "F.Fab")
		)
		(fp_line
			(start -0.12065 0.3048)
			(end -0.67945 0.3048)
			(stroke
				(width 0.1)
				(type default)
			)
			(layer "F.Fab")
		)
		(fp_line
			(start 0.120396 0.2794)
			(end -0.12065 0.2794)
			(stroke
				(width 0.1)
				(type default)
			)
			(layer "F.Fab")
		)
		(fp_line
			(start 0.120396 0.3048)
			(end 0.120396 0.2794)
			(stroke
				(width 0.1)
				(type default)
			)
			(layer "F.Fab")
		)
		(fp_line
			(start 0.12065 -0.3048)
			(end 0.67945 -0.3048)
			(stroke
				(width 0.1)
				(type default)
			)
			(layer "F.Fab")
		)
		(fp_line
			(start 0.12065 -0.2794)
			(end 0.12065 -0.3048)
			(stroke
				(width 0.1)
				(type default)
			)
			(layer "F.Fab")
		)
		(fp_line
			(start 0.67945 -0.3048)
			(end 0.67945 0.3048)
			(stroke
				(width 0.1)
				(type default)
			)
			(layer "F.Fab")
		)
		(fp_line
			(start 0.67945 0.3048)
			(end 0.120396 0.3048)
			(stroke
				(width 0.1)
				(type default)
			)
			(layer "F.Fab")
		)
		(pad "1" smd circle
			(at -0.40005 0)
			(size 0 0)
			(layers "F.Cu" "F.Mask" "F.Paste")
			(net "SMB_VR_3V3AUX_SCL_R")
		)
		(pad "2" smd circle
			(at 0.40005 0)
			(size 0 0)
			(layers "F.Cu" "F.Mask" "F.Paste")
			(net "SMB_VR_3V3AUX_SCL_R3")
		)
	)
)
